# TIMECARD (Time Appliance Project (Time Card)) — schematic netlist excerpt (pin names and nets, part order shuffled) for the footprints in the layout excerpt that follows; sources: Cadence DE-HDL packaged netlist, KiCad conversion of R4006-B0001-02_R01.brd

R311  RESISTOR  0OHM -  pkg SMC_0402R_H016  page 16 : \1\ = RGB_LED_I2C_SCL ; \2\ = R_PCA9546_I2C_SCL
R407  RESISTOR  33OHM 1%  pkg SMC_0402R_H016  page 17 : \1\ = LM75B_I2C_SDA ; \2\ = R_LM75B_3_I2C_SDA

(kicad_pcb
	(version 20260206)
	(generator "pcbnew")
	(generator_version "10.0")
	(general
		(thickness 1.6)
		(legacy_teardrops no)
	)
	(paper "A4")
	(title_block
		(title "timecard-production-celestica-r4006 — R4006-B0001-02_R01.brd")
		(comment 1 "Time Appliance Project (Time Card) / footprints 566-567 of 1113")
	)
	(layers
		(0 "F.Cu" signal "TOP")
		(4 "In1.Cu" signal "L02_GND1")
		(6 "In2.Cu" signal "L03_SIG1")
		(8 "In3.Cu" signal "L04_GND2")
		(10 "In4.Cu" signal "L05_VCC1")
		(12 "In5.Cu" signal "L06_VCC2")
		(14 "In6.Cu" signal "L07_GND3")
		(16 "In7.Cu" signal "L08_SIG2")
		(18 "In8.Cu" signal "L09_GND4")
		(2 "B.Cu" signal "BOTTOM")
		(9 "F.Adhes" user "F.Adhesive")
		(11 "B.Adhes" user "B.Adhesive")
		(13 "F.Paste" user "Package Geometry/Pastemask Top")
		(15 "B.Paste" user "Package Geometry/Pastemask Bottom")
		(5 "F.SilkS" user "Ref Des/Silkscreen Top")
		(7 "B.SilkS" user "Ref Des/Silkscreen Bottom")
		(1 "F.Mask" user "Board Geometry/Soldermask Top")
		(3 "B.Mask" user "Board Geometry/Soldermask Bottom")
		(17 "Dwgs.User" user "User.Drawings")
		(19 "Cmts.User" user "User.Comments")
		(21 "Eco1.User" user "User.Eco1")
		(23 "Eco2.User" user "User.Eco2")
		(25 "Edge.Cuts" user "Board Geometry/Outline")
		(27 "Margin" user)
		(31 "F.CrtYd" user "Package Geometry/Place Bound Top")
		(29 "B.CrtYd" user "Package Geometry/Place Bound Bottom")
		(35 "F.Fab" user "Ref Des/Assembly Top")
		(33 "B.Fab" user "Ref Des/Assembly Bottom")
	)
	(footprint ""
		(layer "F.Cu")
		(at 150.749 -27.432)
		(property "Reference" "R407"
			(at -0.762 -2.11963 0)
			(unlocked yes)
			(layer "F.SilkS")
			(effects
				(font
					(size 0.7874 0.5842)
					(thickness 0.1524)
				)
			)
		)
		(property "Value" "VAL*"
			(at 0.02032 2.13233 0)
			(unlocked yes)
			(layer "F.Fab")
			(hide yes)
			(effects
				(font
					(size 0.7874 0.5842)
					(thickness 0.1524)
				)
			)
		)
		(property "Tolerance" "TOL*"
			(at 0.044704 3.05435 0)
			(unlocked yes)
			(layer "Cmts.User")
			(hide yes)
			(effects
				(font
					(size 0.7874 0.5842)
					(thickness 0.1524)
				)
			)
		)
		(property "User Part Number" "PARTNUM*"
			(at 0.02032 4.024884 0)
			(unlocked yes)
			(layer "Cmts.User")
			(hide yes)
			(effects
				(font
					(size 0.7874 0.5842)
					(thickness 0.1524)
				)
			)
		)
		(property "Device Type" "RESISTOR-G155-133R0-01,33OHM,1%"
			(at 0.008382 1.210564 0)
			(unlocked yes)
			(layer "F.Fab")
			(hide yes)
			(effects
				(font
					(size 0.7874 0.5842)
					(thickness 0.1524)
				)
			)
		)
		(duplicate_pad_numbers_are_jumpers no)
		(fp_line
			(start -1.143 -0.5588)
			(end -1.143 0.5588)
			(stroke
				(width 0.1)
				(type default)
			)
			(layer "F.SilkS")
		)
		(fp_line
			(start -1.143 0.5588)
			(end 1.143 0.5588)
			(stroke
				(width 0.1)
				(type default)
			)
			(layer "F.SilkS")
		)
		(fp_line
			(start 1.143 -0.5588)
			(end -1.143 -0.5588)
			(stroke
				(width 0.1)
				(type default)
			)
			(layer "F.SilkS")
		)
		(fp_line
			(start 1.143 0.5588)
			(end 1.143 -0.5588)
			(stroke
				(width 0.1)
				(type default)
			)
			(layer "F.SilkS")
		)
		(fp_rect
			(start -1.143 0.5588)
			(end 1.143 -0.5588)
			(stroke
				(width 0)
				(type default)
			)
			(fill no)
			(layer "F.CrtYd")
		)
		(fp_line
			(start -0.508 -0.3048)
			(end -0.508 0.3048)
			(stroke
				(width 0.1)
				(type default)
			)
			(layer "F.Fab")
		)
		(fp_line
			(start -0.508 0.3048)
			(end 0.508 0.3048)
			(stroke
				(width 0.1)
				(type default)
			)
			(layer "F.Fab")
		)
		(fp_line
			(start 0.508 -0.3048)
			(end -0.508 -0.3048)
			(stroke
				(width 0.1)
				(type default)
			)
			(layer "F.Fab")
		)
		(fp_line
			(start 0.508 0.3048)
			(end 0.508 -0.3048)
			(stroke
				(width 0.1)
				(type default)
			)
			(layer "F.Fab")
		)
		(pad "1" smd rect
			(at -0.5334 0)
			(size 0.7112 0.6096)
			(layers "F.Cu" "F.Mask" "F.Paste")
			(net "LM75B_I2C_SDA")
		)
		(pad "2" smd rect
			(at 0.5334 0)
			(size 0.7112 0.6096)
			(layers "F.Cu" "F.Mask" "F.Paste")
			(net "R_LM75B_3_I2C_SDA")
		)
		(zone
			(layer "F.Cu")
			(hatch none 0.5)
			(connect_pads
				(clearance 0)
			)
			(min_thickness 0.25)
			(keepout
				(tracks not_allowed)
				(vias allowed)
				(pads allowed)
				(copperpour not_allowed)
				(footprints allowed)
			)
			(placement
				(enabled no)
				(sheetname "")
			)
			(fill
				(thermal_gap 0.5)
				(thermal_bridge_width 0.5)
				(island_removal_mode 0)
			)
			(polygon
				(pts
					(xy 150.6728 -27.1272) (xy 150.8252 -27.1272) (xy 150.8252 -27.7368) (xy 150.6728 -27.7368)
				)
			)
		)
		(zone
			(layer "F.Cu")
			(hatch none 0.5)
			(connect_pads
				(clearance 0)
			)
			(min_thickness 0.25)
			(keepout
				(tracks allowed)
				(vias not_allowed)
				(pads allowed)
				(copperpour not_allowed)
				(footprints allowed)
			)
			(placement
				(enabled no)
				(sheetname "")
			)
			(fill
				(thermal_gap 0.5)
				(thermal_bridge_width 0.5)
				(island_removal_mode 0)
			)
			(polygon
				(pts
					(xy 150.6728 -27.1272) (xy 150.8252 -27.1272) (xy 150.8252 -27.7368) (xy 150.6728 -27.7368)
				)
			)
		)
	)
	(footprint ""
		(layer "F.Cu")
		(at 74.0918 -84.6328)
		(property "Reference" "R311"
			(at -0.1778 -3.33883 0)
			(unlocked yes)
			(layer "F.SilkS")
			(effects
				(font
					(size 0.7874 0.5842)
					(thickness 0.1524)
				)
			)
		)
		(property "Value" "VAL*"
			(at 0.02032 2.13233 0)
			(unlocked yes)
			(layer "F.Fab")
			(hide yes)
			(effects
				(font
					(size 0.7874 0.5842)
					(thickness 0.1524)
				)
			)
		)
		(property "Tolerance" "TOL*"
			(at 0.044704 3.05435 0)
			(unlocked yes)
			(layer "Cmts.User")
			(hide yes)
			(effects
				(font
					(size 0.7874 0.5842)
					(thickness 0.1524)
				)
			)
		)
		(property "User Part Number" "PARTNUM*"
			(at 0.02032 4.024884 0)
			(unlocked yes)
			(layer "Cmts.User")
			(hide yes)
			(effects
				(font
					(size 0.7874 0.5842)
					(thickness 0.1524)
				)
			)
		)
		(property "Device Type" "RESISTOR-G155-100R0-J0,0OHM,-"
			(at 0.008382 1.210564 0)
			(unlocked yes)
			(layer "F.Fab")
			(hide yes)
			(effects
				(font
					(size 0.7874 0.5842)
					(thickness 0.1524)
				)
			)
		)
		(duplicate_pad_numbers_are_jumpers no)
		(fp_line
			(start -1.143 -0.5588)
			(end -1.143 0.5588)
			(stroke
				(width 0.1)
				(type default)
			)
			(layer "F.SilkS")
		)
		(fp_line
			(start -1.143 0.5588)
			(end 1.143 0.5588)
			(stroke
				(width 0.1)
				(type default)
			)
			(layer "F.SilkS")
		)
		(fp_line
			(start 1.143 -0.5588)
			(end -1.143 -0.5588)
			(stroke
				(width 0.1)
				(type default)
			)
			(layer "F.SilkS")
		)
		(fp_line
			(start 1.143 0.5588)
			(end 1.143 -0.5588)
			(stroke
				(width 0.1)
				(type default)
			)
			(layer "F.SilkS")
		)
		(fp_poly
			(pts
				(xy -1.143 0.5588) (xy 1.143 0.5588) (xy 1.143 -0.5588) (xy -1.143 -0.5588)
			)
			(stroke
				(width 0)
				(type default)
			)
			(fill no)
			(layer "F.CrtYd")
		)
		(fp_line
			(start -0.508 -0.3048)
			(end -0.508 0.3048)
			(stroke
				(width 0.1)
				(type default)
			)
			(layer "F.Fab")
		)
		(fp_line
			(start -0.508 0.3048)
			(end 0.508 0.3048)
			(stroke
				(width 0.1)
				(type default)
			)
			(layer "F.Fab")
		)
		(fp_line
			(start 0.508 -0.3048)
			(end -0.508 -0.3048)
			(stroke
				(width 0.1)
				(type default)
			)
			(layer "F.Fab")
		)
		(fp_line
			(start 0.508 0.3048)
			(end 0.508 -0.3048)
			(stroke
				(width 0.1)
				(type default)
			)
			(layer "F.Fab")
		)
		(pad "1" smd rect
			(at -0.5334 0)
			(size 0.7112 0.6096)
			(layers "F.Cu" "F.Mask" "F.Paste")
			(net "RGB_LED_I2C_SCL")
		)
		(pad "2" smd rect
			(at 0.5334 0)
			(size 0.7112 0.6096)
			(layers "F.Cu" "F.Mask" "F.Paste")
			(net "R_PCA9546_I2C_SCL")
		)
		(zone
			(layer "F.Cu")
			(hatch none 0.5)
			(connect_pads
				(clearance 0)
			)
			(min_thickness 0.25)
			(keepout
				(tracks not_allowed)
				(vias allowed)
				(pads allowed)
				(copperpour not_allowed)
				(footprints allowed)
			)
			(placement
				(enabled no)
				(sheetname "")
			)
			(fill
				(thermal_gap 0.5)
				(thermal_bridge_width 0.5)
				(island_removal_mode 0)
			)
			(polygon
				(pts
					(xy 74.0156 -84.328) (xy 74.168 -84.328) (xy 74.168 -84.9376) (xy 74.0156 -84.9376)
				)
			)
		)
		(zone
			(layer "F.Cu")
			(hatch none 0.5)
			(connect_pads
				(clearance 0)
			)
			(min_thickness 0.25)
			(keepout
				(tracks allowed)
				(vias not_allowed)
				(pads allowed)
				(copperpour not_allowed)
				(footprints allowed)
			)
			(placement
				(enabled no)
				(sheetname "")
			)
			(fill
				(thermal_gap 0.5)
				(thermal_bridge_width 0.5)
				(island_removal_mode 0)
			)
			(polygon
				(pts
					(xy 74.0156 -84.328) (xy 74.168 -84.328) (xy 74.168 -84.9376) (xy 74.0156 -84.9376)
				)
			)
		)
	)
)
